(kicad_pcb
	(version 20260206)
	(generator "pcbnew")
	(generator_version "10.0")
	(general
		(thickness 1.6)
		(legacy_teardrops no)
	)
	(paper "A4")
	(title_block
		(title "03242023_DA0F0TMBIJ0_F0T_Motherboard_J_brd_V01_OCP.brd")
		(comment 1 "Grand Teton / footprints 4003-4007 of 6105")
	)
	(layers
		(0 "F.Cu" signal "TOP")
		(4 "In1.Cu" signal "GND")
		(6 "In2.Cu" signal "IN1")
		(8 "In3.Cu" signal "GND1")
		(10 "In4.Cu" signal "IN2")
		(12 "In5.Cu" signal "GND2")
		(14 "In6.Cu" signal "IN3")
		(16 "In7.Cu" signal "GND3")
		(18 "In8.Cu" signal "VCC")
		(20 "In9.Cu" signal "VCC1")
		(22 "In10.Cu" signal "GND4")
		(24 "In11.Cu" signal "IN4")
		(26 "In12.Cu" signal "GND5")
		(28 "In13.Cu" signal "IN5")
		(30 "In14.Cu" signal "GND6")
		(32 "In15.Cu" signal "IN6")
		(34 "In16.Cu" signal "GND7")
		(2 "B.Cu" signal "BOTTOM")
		(9 "F.Adhes" user "F.Adhesive")
		(11 "B.Adhes" user "B.Adhesive")
		(13 "F.Paste" user "Package Geometry/Pastemask Top")
		(15 "B.Paste" user "Package Geometry/Pastemask Bottom")
		(5 "F.SilkS" user "Ref Des/Silkscreen Top")
		(7 "B.SilkS" user "Ref Des/Silkscreen Bottom")
		(1 "F.Mask" user "Board Geometry/Soldermask Top")
		(3 "B.Mask" user "Board Geometry/Soldermask Bottom")
		(17 "Dwgs.User" user "User.Drawings")
		(19 "Cmts.User" user "User.Comments")
		(21 "Eco1.User" user "User.Eco1")
		(23 "Eco2.User" user "User.Eco2")
		(25 "Edge.Cuts" user "Board Geometry/Outline")
		(27 "Margin" user)
		(31 "F.CrtYd" user "Package Geometry/Place Bound Top")
		(29 "B.CrtYd" user "Package Geometry/Place Bound Bottom")
		(35 "F.Fab" user "Ref Des/Assembly Top")
		(33 "B.Fab" user "Ref Des/Assembly Bottom")
	)
	(footprint ""
		(layer "F.Cu")
		(at 367.44783 -260.364986 -90)
		(property "Reference" "C414"
			(at 0 0 270)
			(layer "F.SilkS")
			(hide yes)
			(effects
				(font
					(size 1.27 1.27)
				)
			)
		)
		(property "Value" ""
			(at 0 0 270)
			(layer "F.Fab")
			(effects
				(font
					(size 1.27 1.27)
				)
			)
		)
		(duplicate_pad_numbers_are_jumpers no)
		(fp_line
			(start -0.7874 0.4064)
			(end -0.7874 -0.4064)
			(stroke
				(width 0.1524)
				(type default)
			)
			(layer "F.SilkS")
		)
		(fp_line
			(start 0.7874 0.4064)
			(end -0.7874 0.4064)
			(stroke
				(width 0.1524)
				(type default)
			)
			(layer "F.SilkS")
		)
		(fp_line
			(start -0.7874 -0.4064)
			(end 0.7874 -0.4064)
			(stroke
				(width 0.1524)
				(type default)
			)
			(layer "F.SilkS")
		)
		(fp_line
			(start 0.7874 -0.4064)
			(end 0.7874 0.4064)
			(stroke
				(width 0.1524)
				(type default)
			)
			(layer "F.SilkS")
		)
		(fp_line
			(start -0.67945 0.3048)
			(end -0.67945 -0.305054)
			(stroke
				(width 0.1)
				(type default)
			)
			(layer "F.Fab")
		)
		(fp_line
			(start -0.12065 0.3048)
			(end -0.67945 0.3048)
			(stroke
				(width 0.1)
				(type default)
			)
			(layer "F.Fab")
		)
		(fp_line
			(start 0.120396 0.3048)
			(end 0.120396 0.2794)
			(stroke
				(width 0.1)
				(type default)
			)
			(layer "F.Fab")
		)
		(fp_line
			(start 0.67945 0.3048)
			(end 0.120396 0.3048)
			(stroke
				(width 0.1)
				(type default)
			)
			(layer "F.Fab")
		)
		(fp_line
			(start -0.12065 0.2794)
			(end -0.12065 0.3048)
			(stroke
				(width 0.1)
				(type default)
			)
			(layer "F.Fab")
		)
		(fp_line
			(start 0.120396 0.2794)
			(end -0.12065 0.2794)
			(stroke
				(width 0.1)
				(type default)
			)
			(layer "F.Fab")
		)
		(fp_line
			(start -0.12065 -0.2794)
			(end 0.12065 -0.2794)
			(stroke
				(width 0.1)
				(type default)
			)
			(layer "F.Fab")
		)
		(fp_line
			(start 0.12065 -0.2794)
			(end 0.12065 -0.3048)
			(stroke
				(width 0.1)
				(type default)
			)
			(layer "F.Fab")
		)
		(fp_line
			(start 0.12065 -0.3048)
			(end 0.67945 -0.3048)
			(stroke
				(width 0.1)
				(type default)
			)
			(layer "F.Fab")
		)
		(fp_line
			(start 0.67945 -0.3048)
			(end 0.67945 0.3048)
			(stroke
				(width 0.1)
				(type default)
			)
			(layer "F.Fab")
		)
		(fp_line
			(start -0.67945 -0.305054)
			(end -0.12065 -0.305054)
			(stroke
				(width 0.1)
				(type default)
			)
			(layer "F.Fab")
		)
		(fp_line
			(start -0.12065 -0.305054)
			(end -0.12065 -0.2794)
			(stroke
				(width 0.1)
				(type default)
			)
			(layer "F.Fab")
		)
		(pad "1" smd circle
			(at -0.40005 0 270)
			(size 0 0)
			(layers "F.Cu" "F.Mask" "F.Paste")
			(net "PVCCINFAON_CPU0")
		)
		(pad "2" smd circle
			(at 0.40005 0 270)
			(size 0 0)
			(layers "F.Cu" "F.Mask" "F.Paste")
			(net "GND")
		)
	)
	(footprint ""
		(layer "F.Cu")
		(at 159.181546 -31.341568 90)
		(property "Reference" "R4458"
			(at 0 0 90)
			(layer "F.SilkS")
			(hide yes)
			(effects
				(font
					(size 1.27 1.27)
				)
			)
		)
		(property "Value" ""
			(at 0 0 90)
			(layer "F.Fab")
			(effects
				(font
					(size 1.27 1.27)
				)
			)
		)
		(duplicate_pad_numbers_are_jumpers no)
		(fp_line
			(start 0.7874 -0.4064)
			(end 0.7874 0.4064)
			(stroke
				(width 0.1524)
				(type default)
			)
			(layer "F.SilkS")
		)
		(fp_line
			(start -0.7874 -0.4064)
			(end 0.7874 -0.4064)
			(stroke
				(width 0.1524)
				(type default)
			)
			(layer "F.SilkS")
		)
		(fp_line
			(start 0.7874 0.4064)
			(end -0.7874 0.4064)
			(stroke
				(width 0.1524)
				(type default)
			)
			(layer "F.SilkS")
		)
		(fp_line
			(start -0.7874 0.4064)
			(end -0.7874 -0.4064)
			(stroke
				(width 0.1524)
				(type default)
			)
			(layer "F.SilkS")
		)
		(fp_line
			(start -0.12065 -0.305054)
			(end -0.12065 -0.2794)
			(stroke
				(width 0.1)
				(type default)
			)
			(layer "F.Fab")
		)
		(fp_line
			(start -0.67945 -0.305054)
			(end -0.12065 -0.305054)
			(stroke
				(width 0.1)
				(type default)
			)
			(layer "F.Fab")
		)
		(fp_line
			(start 0.67945 -0.3048)
			(end 0.67945 0.3048)
			(stroke
				(width 0.1)
				(type default)
			)
			(layer "F.Fab")
		)
		(fp_line
			(start 0.12065 -0.3048)
			(end 0.67945 -0.3048)
			(stroke
				(width 0.1)
				(type default)
			)
			(layer "F.Fab")
		)
		(fp_line
			(start 0.12065 -0.2794)
			(end 0.12065 -0.3048)
			(stroke
				(width 0.1)
				(type default)
			)
			(layer "F.Fab")
		)
		(fp_line
			(start -0.12065 -0.2794)
			(end 0.12065 -0.2794)
			(stroke
				(width 0.1)
				(type default)
			)
			(layer "F.Fab")
		)
		(fp_line
			(start 0.120396 0.2794)
			(end -0.12065 0.2794)
			(stroke
				(width 0.1)
				(type default)
			)
			(layer "F.Fab")
		)
		(fp_line
			(start -0.12065 0.2794)
			(end -0.12065 0.3048)
			(stroke
				(width 0.1)
				(type default)
			)
			(layer "F.Fab")
		)
		(fp_line
			(start 0.67945 0.3048)
			(end 0.120396 0.3048)
			(stroke
				(width 0.1)
				(type default)
			)
			(layer "F.Fab")
		)
		(fp_line
			(start 0.120396 0.3048)
			(end 0.120396 0.2794)
			(stroke
				(width 0.1)
				(type default)
			)
			(layer "F.Fab")
		)
		(fp_line
			(start -0.12065 0.3048)
			(end -0.67945 0.3048)
			(stroke
				(width 0.1)
				(type default)
			)
			(layer "F.Fab")
		)
		(fp_line
			(start -0.67945 0.3048)
			(end -0.67945 -0.305054)
			(stroke
				(width 0.1)
				(type default)
			)
			(layer "F.Fab")
		)
		(pad "1" smd circle
			(at -0.40005 0 90)
			(size 0 0)
			(layers "F.Cu" "F.Mask" "F.Paste")
			(net "P3V3_AUX")
		)
		(pad "2" smd circle
			(at 0.40005 0 90)
			(size 0 0)
			(layers "F.Cu" "F.Mask" "F.Paste")
			(net "USB_HUB_2_OVCUR3")
		)
	)
	(footprint ""
		(layer "F.Cu")
		(at 170.23588 -433.923948)
		(property "Reference" "R3457"
			(at 0 0 0)
			(layer "F.SilkS")
			(hide yes)
			(effects
				(font
					(size 1.27 1.27)
				)
			)
		)
		(property "Value" ""
			(at 0 0 0)
			(layer "F.Fab")
			(effects
				(font
					(size 1.27 1.27)
				)
			)
		)
		(duplicate_pad_numbers_are_jumpers no)
		(fp_line
			(start -0.7874 -0.4064)
			(end 0.7874 -0.4064)
			(stroke
				(width 0.1524)
				(type default)
			)
			(layer "F.SilkS")
		)
		(fp_line
			(start -0.7874 0.4064)
			(end -0.7874 -0.4064)
			(stroke
				(width 0.1524)
				(type default)
			)
			(layer "F.SilkS")
		)
		(fp_line
			(start 0.7874 -0.4064)
			(end 0.7874 0.4064)
			(stroke
				(width 0.1524)
				(type default)
			)
			(layer "F.SilkS")
		)
		(fp_line
			(start 0.7874 0.4064)
			(end -0.7874 0.4064)
			(stroke
				(width 0.1524)
				(type default)
			)
			(layer "F.SilkS")
		)
		(fp_line
			(start -0.67945 -0.305054)
			(end -0.12065 -0.305054)
			(stroke
				(width 0.1)
				(type default)
			)
			(layer "F.Fab")
		)
		(fp_line
			(start -0.67945 0.3048)
			(end -0.67945 -0.305054)
			(stroke
				(width 0.1)
				(type default)
			)
			(layer "F.Fab")
		)
		(fp_line
			(start -0.12065 -0.305054)
			(end -0.12065 -0.2794)
			(stroke
				(width 0.1)
				(type default)
			)
			(layer "F.Fab")
		)
		(fp_line
			(start -0.12065 -0.2794)
			(end 0.12065 -0.2794)
			(stroke
				(width 0.1)
				(type default)
			)
			(layer "F.Fab")
		)
		(fp_line
			(start -0.12065 0.2794)
			(end -0.12065 0.3048)
			(stroke
				(width 0.1)
				(type default)
			)
			(layer "F.Fab")
		)
		(fp_line
			(start -0.12065 0.3048)
			(end -0.67945 0.3048)
			(stroke
				(width 0.1)
				(type default)
			)
			(layer "F.Fab")
		)
		(fp_line
			(start 0.120396 0.2794)
			(end -0.12065 0.2794)
			(stroke
				(width 0.1)
				(type default)
			)
			(layer "F.Fab")
		)
		(fp_line
			(start 0.120396 0.3048)
			(end 0.120396 0.2794)
			(stroke
				(width 0.1)
				(type default)
			)
			(layer "F.Fab")
		)
		(fp_line
			(start 0.12065 -0.3048)
			(end 0.67945 -0.3048)
			(stroke
				(width 0.1)
				(type default)
			)
			(layer "F.Fab")
		)
		(fp_line
			(start 0.12065 -0.2794)
			(end 0.12065 -0.3048)
			(stroke
				(width 0.1)
				(type default)
			)
			(layer "F.Fab")
		)
		(fp_line
			(start 0.67945 -0.3048)
			(end 0.67945 0.3048)
			(stroke
				(width 0.1)
				(type default)
			)
			(layer "F.Fab")
		)
		(fp_line
			(start 0.67945 0.3048)
			(end 0.120396 0.3048)
			(stroke
				(width 0.1)
				(type default)
			)
			(layer "F.Fab")
		)
		(pad "1" smd circle
			(at -0.40005 0)
			(size 0 0)
			(layers "F.Cu" "F.Mask" "F.Paste")
			(net "GPU_BASE_STBY_EN_BUF_R")
		)
		(pad "2" smd circle
			(at 0.40005 0)
			(size 0 0)
			(layers "F.Cu" "F.Mask" "F.Paste")
			(net "GND")
		)
	)
	(footprint ""
		(layer "F.Cu")
		(at 83.30057 -55.432706 -90)
		(property "Reference" "PU200"
			(at 0.436626 7.02818 0)
			(unlocked yes)
			(layer "F.SilkS")
			(effects
				(font
					(size 0.7874 0.5842)
					(thickness 0.1524)
				)
				(justify left)
			)
		)
		(property "Value" ""
			(at 0 0 270)
			(layer "F.Fab")
			(effects
				(font
					(size 1.27 1.27)
				)
			)
		)
		(duplicate_pad_numbers_are_jumpers no)
		(fp_line
			(start -1.774952 1.039876)
			(end 1.774952 1.039876)
			(stroke
				(width 0.1524)
				(type default)
			)
			(layer "F.SilkS")
		)
		(fp_line
			(start 1.774952 1.039876)
			(end 1.774952 -1.039876)
			(stroke
				(width 0.1524)
				(type default)
			)
			(layer "F.SilkS")
		)
		(fp_line
			(start -1.774952 -1.039876)
			(end -1.774952 1.039876)
			(stroke
				(width 0.1524)
				(type default)
			)
			(layer "F.SilkS")
		)
		(fp_line
			(start 1.774952 -1.039876)
			(end -1.774952 -1.039876)
			(stroke
				(width 0.1524)
				(type default)
			)
			(layer "F.SilkS")
		)
		(fp_poly
			(pts
				(xy -1.769872 -1.039876) (xy -1.769872 -0.249936) (xy -2.531872 -0.249936) (xy -2.531872 -1.801876)
				(xy -0.999998 -1.801876) (xy -0.999998 -1.039876)
			)
			(stroke
				(width 0)
				(type default)
			)
			(fill yes)
			(layer "F.SilkS")
		)
		(fp_line
			(start -1.769872 1.039876)
			(end 1.769872 1.039876)
			(stroke
				(width 0.1)
				(type default)
			)
			(layer "F.Fab")
		)
		(fp_line
			(start 1.769872 1.039876)
			(end 1.769872 -1.039876)
			(stroke
				(width 0.1)
				(type default)
			)
			(layer "F.Fab")
		)
		(fp_line
			(start -1.769872 -1.039876)
			(end -1.769872 1.039876)
			(stroke
				(width 0.1)
				(type default)
			)
			(layer "F.Fab")
		)
		(fp_line
			(start 1.769872 -1.039876)
			(end -1.769872 -1.039876)
			(stroke
				(width 0.1)
				(type default)
			)
			(layer "F.Fab")
		)
		(fp_poly
			(pts
				(xy -1.769872 -1.039876) (xy -0.999998 -1.039876) (xy -0.999998 -1.801876) (xy -2.531872 -1.801876)
				(xy -2.531872 -0.249936) (xy -1.769872 -0.249936)
			)
			(stroke
				(width 0)
				(type default)
			)
			(fill yes)
			(layer "F.Fab")
		)
		(pad "A1" smd circle
			(at -1.500124 -0.750062 270)
			(size 0.2286 0.2286)
			(layers "F.Cu" "F.Mask" "F.Paste")
			(net "P3V3_OCP_SENSE_2")
		)
		(pad "A2" smd circle
			(at -0.999998 -0.750062 270)
			(size 0.2286 0.2286)
			(layers "F.Cu" "F.Mask" "F.Paste")
			(net "P3V3_OCP_VCC_2")
		)
		(pad "A3" smd circle
			(at -0.499872 -0.750062 270)
			(size 0.2286 0.2286)
			(layers "F.Cu" "F.Mask" "F.Paste")
			(net "P3V3_AUX")
		)
		(pad "A4" smd circle
			(at 0 -0.750062 270)
			(size 0.2286 0.2286)
			(layers "F.Cu" "F.Mask" "F.Paste")
			(net "P3V3_OCP_V3_2_R")
		)
		(pad "A5" smd circle
			(at 0.499872 -0.750062 270)
			(size 0.2286 0.2286)
			(layers "F.Cu" "F.Mask" "F.Paste")
			(net "P3V3_AUX")
		)
		(pad "A6" smd circle
			(at 0.999998 -0.750062 270)
			(size 0.2286 0.2286)
			(layers "F.Cu" "F.Mask" "F.Paste")
			(net "P3V3_OCP_GATE_2")
		)
		(pad "A7" smd circle
			(at 1.500124 -0.750062 270)
			(size 0.2286 0.2286)
			(layers "F.Cu" "F.Mask" "F.Paste")
			(net "GND")
		)
		(pad "B1" smd circle
			(at -1.500124 -0.249936 270)
			(size 0.2286 0.2286)
			(layers "F.Cu" "F.Mask" "F.Paste")
			(net "P3V3_OCP_CB_2")
		)
		(pad "B2" smd circle
			(at -0.999998 -0.249936 270)
			(size 0.2286 0.2286)
			(layers "F.Cu" "F.Mask" "F.Paste")
			(net "GND")
		)
		(pad "B3" smd circle
			(at -0.499872 -0.249936 270)
			(size 0.2286 0.2286)
			(layers "F.Cu" "F.Mask" "F.Paste")
			(net "P3V3_AUX")
		)
		(pad "B4" smd circle
			(at 0 -0.249936 270)
			(size 0.2286 0.2286)
			(layers "F.Cu" "F.Mask" "F.Paste")
			(net "P3V3_OCP_V3_2_R")
		)
		(pad "B5" smd circle
			(at 0.499872 -0.249936 270)
			(size 0.2286 0.2286)
			(layers "F.Cu" "F.Mask" "F.Paste")
			(net "P3V3_AUX")
		)
		(pad "B6" smd circle
			(at 0.999998 -0.249936 270)
			(size 0.2286 0.2286)
			(layers "F.Cu" "F.Mask" "F.Paste")
			(net "P3V3_OCP_V3_2_R")
		)
		(pad "B7" smd circle
			(at 1.500124 -0.249936 270)
			(size 0.2286 0.2286)
			(layers "F.Cu" "F.Mask" "F.Paste")
			(net "GND")
		)
		(pad "C1" smd circle
			(at -1.500124 0.249936 270)
			(size 0.2286 0.2286)
			(layers "F.Cu" "F.Mask" "F.Paste")
			(net "GND")
		)
		(pad "C2" smd circle
			(at -0.999998 0.249936 270)
			(size 0.2286 0.2286)
			(layers "F.Cu" "F.Mask" "F.Paste")
			(net "GND")
		)
		(pad "C3" smd circle
			(at -0.499872 0.249936 270)
			(size 0.2286 0.2286)
			(layers "F.Cu" "F.Mask" "F.Paste")
			(net "P3V3_AUX")
		)
		(pad "C4" smd circle
			(at 0 0.249936 270)
			(size 0.2286 0.2286)
			(layers "F.Cu" "F.Mask" "F.Paste")
			(net "P3V3_OCP_V3_2_R")
		)
		(pad "C5" smd circle
			(at 0.499872 0.249936 270)
			(size 0.2286 0.2286)
			(layers "F.Cu" "F.Mask" "F.Paste")
			(net "P3V3_AUX")
		)
		(pad "C6" smd circle
			(at 0.999998 0.249936 270)
			(size 0.2286 0.2286)
			(layers "F.Cu" "F.Mask" "F.Paste")
			(net "P3V3_OCP_V3_2_R")
		)
		(pad "C7" smd circle
			(at 1.500124 0.249936 270)
			(size 0.2286 0.2286)
			(layers "F.Cu" "F.Mask" "F.Paste")
			(net "P3V3_OCP_FAULT_2")
		)
		(pad "D1" smd circle
			(at -1.500124 0.750062 270)
			(size 0.2286 0.2286)
			(layers "F.Cu" "F.Mask" "F.Paste")
			(net "P3V3_OCP_REG_2")
		)
		(pad "D2" smd circle
			(at -0.999998 0.750062 270)
			(size 0.2286 0.2286)
			(layers "F.Cu" "F.Mask" "F.Paste")
			(net "P3V3_OCP_UV_2")
		)
		(pad "D3" smd circle
			(at -0.499872 0.750062 270)
			(size 0.2286 0.2286)
			(layers "F.Cu" "F.Mask" "F.Paste")
			(net "P3V3_OCP_OV_2")
		)
		(pad "D4" smd circle
			(at 0 0.750062 270)
			(size 0.2286 0.2286)
			(layers "F.Cu" "F.Mask" "F.Paste")
			(net "P3V3_OCP_V3_2_R")
		)
		(pad "D5" smd circle
			(at 0.499872 0.750062 270)
			(size 0.2286 0.2286)
			(layers "F.Cu" "F.Mask" "F.Paste")
			(net "P3V3_AUX")
		)
		(pad "D6" smd circle
			(at 0.999998 0.750062 270)
			(size 0.2286 0.2286)
			(layers "F.Cu" "F.Mask" "F.Paste")
			(net "P3V3_OCP_V3_2_R")
		)
		(pad "D7" smd circle
			(at 1.500124 0.750062 270)
			(size 0.2286 0.2286)
			(layers "F.Cu" "F.Mask" "F.Paste")
			(net "P3V3_OCP_PWRGD_2")
		)
	)
	(footprint ""
		(layer "F.Cu")
		(at 134.04088 -92.674948 90)
		(property "Reference" "R204"
			(at 0 0 90)
			(layer "F.SilkS")
			(hide yes)
			(effects
				(font
					(size 1.27 1.27)
				)
			)
		)
		(property "Value" ""
			(at 0 0 90)
			(layer "F.Fab")
			(effects
				(font
					(size 1.27 1.27)
				)
			)
		)
		(duplicate_pad_numbers_are_jumpers no)
		(fp_line
			(start 0.7874 -0.4064)
			(end 0.7874 0.4064)
			(stroke
				(width 0.1524)
				(type default)
			)
			(layer "F.SilkS")
		)
		(fp_line
			(start -0.7874 -0.4064)
			(end 0.7874 -0.4064)
			(stroke
				(width 0.1524)
				(type default)
			)
			(layer "F.SilkS")
		)
		(fp_line
			(start 0.7874 0.4064)
			(end -0.7874 0.4064)
			(stroke
				(width 0.1524)
				(type default)
			)
			(layer "F.SilkS")
		)
		(fp_line
			(start -0.7874 0.4064)
			(end -0.7874 -0.4064)
			(stroke
				(width 0.1524)
				(type default)
			)
			(layer "F.SilkS")
		)
		(fp_line
			(start -0.12065 -0.305054)
			(end -0.12065 -0.2794)
			(stroke
				(width 0.1)
				(type default)
			)
			(layer "F.Fab")
		)
		(fp_line
			(start -0.67945 -0.305054)
			(end -0.12065 -0.305054)
			(stroke
				(width 0.1)
				(type default)
			)
			(layer "F.Fab")
		)
		(fp_line
			(start 0.67945 -0.3048)
			(end 0.67945 0.3048)
			(stroke
				(width 0.1)
				(type default)
			)
			(layer "F.Fab")
		)
		(fp_line
			(start 0.12065 -0.3048)
			(end 0.67945 -0.3048)
			(stroke
				(width 0.1)
				(type default)
			)
			(layer "F.Fab")
		)
		(fp_line
			(start 0.12065 -0.2794)
			(end 0.12065 -0.3048)
			(stroke
				(width 0.1)
				(type default)
			)
			(layer "F.Fab")
		)
		(fp_line
			(start -0.12065 -0.2794)
			(end 0.12065 -0.2794)
			(stroke
				(width 0.1)
				(type default)
			)
			(layer "F.Fab")
		)
		(fp_line
			(start 0.120396 0.2794)
			(end -0.12065 0.2794)
			(stroke
				(width 0.1)
				(type default)
			)
			(layer "F.Fab")
		)
		(fp_line
			(start -0.12065 0.2794)
			(end -0.12065 0.3048)
			(stroke
				(width 0.1)
				(type default)
			)
			(layer "F.Fab")
		)
		(fp_line
			(start 0.67945 0.3048)
			(end 0.120396 0.3048)
			(stroke
				(width 0.1)
				(type default)
			)
			(layer "F.Fab")
		)
		(fp_line
			(start 0.120396 0.3048)
			(end 0.120396 0.2794)
			(stroke
				(width 0.1)
				(type default)
			)
			(layer "F.Fab")
		)
		(fp_line
			(start -0.12065 0.3048)
			(end -0.67945 0.3048)
			(stroke
				(width 0.1)
				(type default)
			)
			(layer "F.Fab")
		)
		(fp_line
			(start -0.67945 0.3048)
			(end -0.67945 -0.305054)
			(stroke
				(width 0.1)
				(type default)
			)
			(layer "F.Fab")
		)
		(pad "1" smd circle
			(at -0.40005 0 90)
			(size 0 0)
			(layers "F.Cu" "F.Mask" "F.Paste")
			(net "H_CPU1_MEMHOT_OUT_LVC1_R_N")
		)
		(pad "2" smd circle
			(at 0.40005 0 90)
			(size 0 0)
			(layers "F.Cu" "F.Mask" "F.Paste")
			(net "H_CPU1_MEMHOT_OUT_VT_R_N")
		)
	)
)
